FILE_TYPE = MACRO_DRAWING;
SET COLOR_WIRE YELLOW;
SET COLOR_PROP MONO;
SET COLOR_DOT WHITE;
SET COLOR_ARC YELLOW;
SET COLOR_BODY GREEN;
SET COLOR_NOTE MONO;
SET PROP_DISPLAY VALUE;
SET PAGE_NUMBER P122;
FORCEADD P1V8_PCH_STBY..1
R 2
(-1450 4925);
FORCEPROP 3 LASTPIN (-1450 4875) SIG_NAME P1V8_PCH_STBY\g
J 0
(-1440 4885);
DISPLAY 0.659574 (-1440 4885);
PAINT MONO (-1440 4885);
DISPLAY INVISIBLE (-1440 4885);
FORCEPROP 1 LAST VOLTAGE 1.8V
J 2
(-1405 4882);
DISPLAY 0.340426 (-1405 4882);
PAINT SKYBLUE (-1405 4882);
DISPLAY INVISIBLE (-1405 4882);
FORCEPROP 2 LAST CDS_LIB mstr_symbols
J 0
(-1450 4925);
PAINT ORANGE (-1450 4925);
DISPLAY INVISIBLE (-1450 4925);
FORCEPROP 1 LAST BODY_TYPE PLUMBING
J 2
(-1405 4882);
DISPLAY 0.340426 (-1405 4882);
PAINT GREEN (-1405 4882);
DISPLAY INVISIBLE (-1405 4882);
FORCEPROP 1 LAST PATH I21
J 2
(-1500 4950);
DISPLAY 0.872340 (-1500 4950);
PAINT AQUA (-1500 4950);
DISPLAY INVISIBLE (-1500 4950);
FORCEPROP 1 LAST HDL_POWER P1V8_PCH_STBY
J 1
(-1450 4975);
DISPLAY 0.872340 (-1450 4975);
PAINT GREEN (-1450 4975);
DISPLAY INVISIBLE (-1450 4975);
FORCEADD P1V05_PCH_STBY..1
(-5650 5225);
FORCEPROP 3 LASTPIN (-5650 5175) SIG_NAME P1V05_PCH_STBY\g
J 0
(-5640 5185);
DISPLAY 0.659574 (-5640 5185);
PAINT MONO (-5640 5185);
DISPLAY INVISIBLE (-5640 5185);
FORCEPROP 1 LAST VOLTAGE 1.05V
J 0
(-5695 5182);
DISPLAY 0.340426 (-5695 5182);
PAINT SKYBLUE (-5695 5182);
DISPLAY INVISIBLE (-5695 5182);
FORCEPROP 2 LAST CDS_LIB mstr_symbols
J 0
(-5650 5225);
PAINT ORANGE (-5650 5225);
DISPLAY INVISIBLE (-5650 5225);
FORCEPROP 1 LAST BODY_TYPE PLUMBING
J 0
(-5695 5182);
DISPLAY 0.340426 (-5695 5182);
PAINT GREEN (-5695 5182);
DISPLAY INVISIBLE (-5695 5182);
FORCEPROP 1 LAST PATH I24
J 0
(-5600 5250);
DISPLAY 0.872340 (-5600 5250);
PAINT AQUA (-5600 5250);
DISPLAY INVISIBLE (-5600 5250);
FORCEPROP 1 LAST HDL_POWER P1V05_PCH_STBY
J 0
(-5650 5275);
DISPLAY 0.872340 (-5650 5275);
PAINT GREEN (-5650 5275);
DISPLAY INVISIBLE (-5650 5275);
FORCEADD OFFPAGE..2
(-1250 2575);
FORCEPROP 2 LAST $XR0 130 
J 0
(-1061 2575);
DISPLAY 0.638298 (-1061 2575);
PAINT MONO (-1061 2575);
FORCEPROP 2 LAST CDS_LIB mstr_standard
J 0
(-1250 2575);
PAINT ORANGE (-1250 2575);
DISPLAY INVISIBLE (-1250 2575);
FORCEPROP 2 LAST BOM_COST SB
J 0
(-950 2625);
DISPLAY 0.744681 (-950 2625);
PAINT MONO (-950 2625);
DISPLAY INVISIBLE (-950 2625);
FORCEPROP 1 LAST OFFPAGE TRUE
J 0
(-925 2450);
DISPLAY 0.872340 (-925 2450);
PAINT GREEN (-925 2450);
DISPLAY INVISIBLE (-925 2450);
FORCEPROP 1 LAST COMMENT_BODY TRUE
J 0
(-1295 2480);
DISPLAY 0.872340 (-1295 2480);
PAINT PEACH (-1295 2480);
DISPLAY INVISIBLE (-1295 2480);
FORCEPROP 2 LAST PATH I46
J 0
(-1075 2650);
DISPLAY 1.021277 (-1075 2650);
PAINT ORANGE (-1075 2650);
DISPLAY INVISIBLE (-1075 2650);
FORCEADD LBG_CORE_QAT_EXT_D..9
(-3900 3075);
FORCEPROP 1 LAST LOCATION U7C1
J 0
(-5000 4850);
DISPLAY 0.617021 (-5000 4850);
PAINT AQUA (-5000 4850);
FORCEPROP 1 LAST PART_NUMBER H91415-002
J 0
(-5350 1175);
DISPLAY 0.617021 (-5350 1175);
PAINT BLUE (-5350 1175);
FORCEPROP 1 LAST MATERIAL IC
J 0
(-5350 4975);
DISPLAY 0.617021 (-5350 4975);
PAINT SKYBLUE (-5350 4975);
FORCEPROP 2 LASTPIN (-2400 2925) $PN AR24
J 0
(-2390 2935);
DISPLAY 0.617021 (-2390 2935);
PAINT ORANGE (-2390 2935);
FORCEPROP 2 LASTPIN (-2400 2875) $PN AN24
J 0
(-2390 2885);
DISPLAY 0.617021 (-2390 2885);
PAINT ORANGE (-2390 2885);
FORCEPROP 2 LASTPIN (-2400 2775) $PN AH24
J 0
(-2390 2785);
DISPLAY 0.617021 (-2390 2785);
PAINT ORANGE (-2390 2785);
FORCEPROP 2 LASTPIN (-2400 2725) $PN BA48
J 0
(-2390 2735);
DISPLAY 0.617021 (-2390 2735);
PAINT ORANGE (-2390 2735);
FORCEPROP 2 LASTPIN (-5400 4775) $PN AK43
J 2
(-5410 4785);
DISPLAY 0.617021 (-5410 4785);
PAINT ORANGE (-5410 4785);
FORCEPROP 2 LASTPIN (-5400 4675) $PN AM43
J 2
(-5410 4685);
DISPLAY 0.617021 (-5410 4685);
PAINT ORANGE (-5410 4685);
FORCEPROP 2 LASTPIN (-5400 4625) $PN AM45
J 2
(-5410 4635);
DISPLAY 0.617021 (-5410 4635);
PAINT ORANGE (-5410 4635);
FORCEPROP 2 LASTPIN (-5400 2075) $PN AM48
J 2
(-5410 2085);
DISPLAY 0.617021 (-5410 2085);
PAINT ORANGE (-5410 2085);
FORCEPROP 2 LASTPIN (-5400 2025) $PN AN50
J 2
(-5410 2035);
DISPLAY 0.617021 (-5410 2035);
PAINT ORANGE (-5410 2035);
FORCEPROP 2 LASTPIN (-5400 2275) $PN AT48
J 2
(-5410 2285);
DISPLAY 0.617021 (-5410 2285);
PAINT ORANGE (-5410 2285);
FORCEPROP 2 LASTPIN (-5400 2325) $PN AU48
J 2
(-5410 2335);
DISPLAY 0.617021 (-5410 2335);
PAINT ORANGE (-5410 2335);
FORCEPROP 2 LASTPIN (-5400 2375) $PN AP48
J 2
(-5410 2385);
DISPLAY 0.617021 (-5410 2385);
PAINT ORANGE (-5410 2385);
FORCEPROP 2 LASTPIN (-5400 2475) $PN AG48
J 2
(-5410 2485);
DISPLAY 0.617021 (-5410 2485);
PAINT ORANGE (-5410 2485);
FORCEPROP 2 LASTPIN (-5400 2525) $PN AE45
J 2
(-5410 2535);
DISPLAY 0.617021 (-5410 2535);
PAINT ORANGE (-5410 2535);
FORCEPROP 2 LASTPIN (-5400 2625) $PN AK27
J 2
(-5410 2635);
DISPLAY 0.617021 (-5410 2635);
PAINT ORANGE (-5410 2635);
FORCEPROP 2 LASTPIN (-2400 3975) $PN AT27
J 0
(-2390 3985);
DISPLAY 0.617021 (-2390 3985);
PAINT ORANGE (-2390 3985);
FORCEPROP 2 LASTPIN (-2400 2475) $PN AP27
J 0
(-2390 2485);
DISPLAY 0.617021 (-2390 2485);
PAINT ORANGE (-2390 2485);
FORCEPROP 2 LASTPIN (-2400 2425) $PN P29
J 0
(-2390 2435);
DISPLAY 0.617021 (-2390 2435);
PAINT ORANGE (-2390 2435);
FORCEPROP 2 LASTPIN (-2400 2325) $PN R31
J 0
(-2390 2335);
DISPLAY 0.617021 (-2390 2335);
PAINT ORANGE (-2390 2335);
FORCEPROP 2 LASTPIN (-2400 2375) $PN P33
J 0
(-2390 2385);
DISPLAY 0.617021 (-2390 2385);
PAINT ORANGE (-2390 2385);
FORCEPROP 2 LASTPIN (-2400 2275) $PN R35
J 0
(-2390 2285);
DISPLAY 0.617021 (-2390 2285);
PAINT ORANGE (-2390 2285);
FORCEPROP 2 LASTPIN (-5400 1675) $PN AE46
J 2
(-5410 1685);
DISPLAY 0.617021 (-5410 1685);
PAINT ORANGE (-5410 1685);
FORCEPROP 2 LASTPIN (-5400 1625) $PN AJ48
J 2
(-5410 1635);
DISPLAY 0.617021 (-5410 1635);
PAINT ORANGE (-5410 1635);
FORCEPROP 2 LASTPIN (-5400 1575) $PN AJ46
J 2
(-5410 1585);
DISPLAY 0.617021 (-5410 1585);
PAINT ORANGE (-5410 1585);
FORCEPROP 2 LASTPIN (-5400 1525) $PN AG45
J 2
(-5410 1535);
DISPLAY 0.617021 (-5410 1535);
PAINT ORANGE (-5410 1535);
FORCEPROP 2 LASTPIN (-5400 1475) $PN W50
J 2
(-5410 1485);
DISPLAY 0.617021 (-5410 1485);
PAINT ORANGE (-5410 1485);
FORCEPROP 2 LASTPIN (-5400 2775) $PN U50
J 2
(-5410 2785);
DISPLAY 0.617021 (-5410 2785);
PAINT ORANGE (-5410 2785);
FORCEPROP 2 LASTPIN (-5400 2725) $PN AH50
J 2
(-5410 2735);
DISPLAY 0.617021 (-5410 2735);
PAINT ORANGE (-5410 2735);
FORCEPROP 2 LASTPIN (-5400 1375) $PN AD50
J 2
(-5410 1385);
DISPLAY 0.617021 (-5410 1385);
PAINT ORANGE (-5410 1385);
FORCEPROP 2 LASTPIN (-5400 4575) $PN AP43
J 2
(-5410 4585);
DISPLAY 0.617021 (-5410 4585);
PAINT ORANGE (-5410 4585);
FORCEPROP 2 LASTPIN (-5400 4525) $PN AP45
J 2
(-5410 4535);
DISPLAY 0.617021 (-5410 4535);
PAINT ORANGE (-5410 4535);
FORCEPROP 2 LASTPIN (-5400 4475) $PN AT43
J 2
(-5410 4485);
DISPLAY 0.617021 (-5410 4485);
PAINT ORANGE (-5410 4485);
FORCEPROP 2 LASTPIN (-5400 4425) $PN AT45
J 2
(-5410 4435);
DISPLAY 0.617021 (-5410 4435);
PAINT ORANGE (-5410 4435);
FORCEPROP 2 LASTPIN (-5400 4375) $PN AU43
J 2
(-5410 4385);
DISPLAY 0.617021 (-5410 4385);
PAINT ORANGE (-5410 4385);
FORCEPROP 2 LASTPIN (-5400 4325) $PN AU45
J 2
(-5410 4335);
DISPLAY 0.617021 (-5410 4335);
PAINT ORANGE (-5410 4335);
FORCEPROP 2 LASTPIN (-5400 4275) $PN AJ43
J 2
(-5410 4285);
DISPLAY 0.617021 (-5410 4285);
PAINT ORANGE (-5410 4285);
FORCEPROP 2 LASTPIN (-5400 4225) $PN AW43
J 2
(-5410 4235);
DISPLAY 0.617021 (-5410 4235);
PAINT ORANGE (-5410 4235);
FORCEPROP 2 LASTPIN (-5400 4175) $PN AW45
J 2
(-5410 4185);
DISPLAY 0.617021 (-5410 4185);
PAINT ORANGE (-5410 4185);
FORCEPROP 2 LASTPIN (-5400 1925) $PN BA39
J 2
(-5410 1935);
DISPLAY 0.617021 (-5410 1935);
PAINT ORANGE (-5410 1935);
FORCEPROP 2 LASTPIN (-5400 1875) $PN BA41
J 2
(-5410 1885);
DISPLAY 0.617021 (-5410 1885);
PAINT ORANGE (-5410 1885);
FORCEPROP 2 LASTPIN (-5400 1825) $PN BB40
J 2
(-5410 1835);
DISPLAY 0.617021 (-5410 1835);
PAINT ORANGE (-5410 1835);
FORCEPROP 2 LASTPIN (-5400 1775) $PN BD38
J 2
(-5410 1785);
DISPLAY 0.617021 (-5410 1785);
PAINT ORANGE (-5410 1785);
FORCEPROP 2 LASTPIN (-2400 4125) $PN BA27
J 0
(-2390 4135);
DISPLAY 0.617021 (-2390 4135);
PAINT ORANGE (-2390 4135);
FORCEPROP 2 LASTPIN (-2400 4075) $PN BA29
J 0
(-2390 4085);
DISPLAY 0.617021 (-2390 4085);
PAINT ORANGE (-2390 4085);
FORCEPROP 2 LASTPIN (-5400 3175) $PN BA30
J 2
(-5410 3185);
DISPLAY 0.617021 (-5410 3185);
PAINT ORANGE (-5410 3185);
FORCEPROP 2 LASTPIN (-5400 3125) $PN BA32
J 2
(-5410 3135);
DISPLAY 0.617021 (-5410 3135);
PAINT ORANGE (-5410 3135);
FORCEPROP 2 LASTPIN (-5400 3075) $PN BA34
J 2
(-5410 3085);
DISPLAY 0.617021 (-5410 3085);
PAINT ORANGE (-5410 3085);
FORCEPROP 2 LASTPIN (-5400 3025) $PN BA36
J 2
(-5410 3035);
DISPLAY 0.617021 (-5410 3035);
PAINT ORANGE (-5410 3035);
FORCEPROP 2 LASTPIN (-5400 2975) $PN BA37
J 2
(-5410 2985);
DISPLAY 0.617021 (-5410 2985);
PAINT ORANGE (-5410 2985);
FORCEPROP 2 LASTPIN (-5400 2925) $PN BB33
J 2
(-5410 2935);
DISPLAY 0.617021 (-5410 2935);
PAINT ORANGE (-5410 2935);
FORCEPROP 2 LASTPIN (-5400 2875) $PN BB37
J 2
(-5410 2885);
DISPLAY 0.617021 (-5410 2885);
PAINT ORANGE (-5410 2885);
FORCEPROP 2 LASTPIN (-2400 3875) $PN AW24
J 0
(-2390 3885);
DISPLAY 0.617021 (-2390 3885);
PAINT ORANGE (-2390 3885);
FORCEPROP 2 LASTPIN (-2400 3825) $PN BE26
J 0
(-2390 3835);
DISPLAY 0.617021 (-2390 3835);
PAINT ORANGE (-2390 3835);
FORCEPROP 2 LASTPIN (-2400 3775) $PN BE40
J 0
(-2390 3785);
DISPLAY 0.617021 (-2390 3785);
PAINT ORANGE (-2390 3785);
FORCEPROP 2 LASTPIN (-2400 3725) $PN BA43
J 0
(-2390 3735);
DISPLAY 0.617021 (-2390 3735);
PAINT ORANGE (-2390 3735);
FORCEPROP 2 LASTPIN (-2400 3675) $PN BE44
J 0
(-2390 3685);
DISPLAY 0.617021 (-2390 3685);
PAINT ORANGE (-2390 3685);
FORCEPROP 2 LASTPIN (-2400 3625) $PN AU27
J 0
(-2390 3635);
DISPLAY 0.617021 (-2390 3635);
PAINT ORANGE (-2390 3635);
FORCEPROP 2 LASTPIN (-2400 3575) $PN BA26
J 0
(-2390 3585);
DISPLAY 0.617021 (-2390 3585);
PAINT ORANGE (-2390 3585);
FORCEPROP 2 LASTPIN (-2400 3525) $PN BA24
J 0
(-2390 3535);
DISPLAY 0.617021 (-2390 3535);
PAINT ORANGE (-2390 3535);
FORCEPROP 2 LASTPIN (-2400 3475) $PN BB26
J 0
(-2390 3485);
DISPLAY 0.617021 (-2390 3485);
PAINT ORANGE (-2390 3485);
FORCEPROP 2 LASTPIN (-2400 3425) $PN AU24
J 0
(-2390 3435);
DISPLAY 0.617021 (-2390 3435);
PAINT ORANGE (-2390 3435);
FORCEPROP 2 LASTPIN (-2400 4775) $PN AK24
J 0
(-2390 4785);
DISPLAY 0.617021 (-2390 4785);
PAINT ORANGE (-2390 4785);
FORCEPROP 2 LASTPIN (-2400 4725) $PN AW27
J 0
(-2390 4735);
DISPLAY 0.617021 (-2390 4735);
PAINT ORANGE (-2390 4735);
FORCEPROP 2 LASTPIN (-2400 4675) $PN AP29
J 0
(-2390 4685);
DISPLAY 0.617021 (-2390 4685);
PAINT ORANGE (-2390 4685);
FORCEPROP 2 LASTPIN (-2400 4625) $PN AM29
J 0
(-2390 4635);
DISPLAY 0.617021 (-2390 4635);
PAINT ORANGE (-2390 4635);
FORCEPROP 2 LASTPIN (-2400 4575) $PN AT29
J 0
(-2390 4585);
DISPLAY 0.617021 (-2390 4585);
PAINT ORANGE (-2390 4585);
FORCEPROP 2 LASTPIN (-2400 4525) $PN AW29
J 0
(-2390 4535);
DISPLAY 0.617021 (-2390 4535);
PAINT ORANGE (-2390 4535);
FORCEPROP 2 LASTPIN (-2400 4475) $PN AU29
J 0
(-2390 4485);
DISPLAY 0.617021 (-2390 4485);
PAINT ORANGE (-2390 4485);
FORCEPROP 2 LASTPIN (-2400 4275) $PN AG27
J 0
(-2390 4285);
DISPLAY 0.617021 (-2390 4285);
PAINT ORANGE (-2390 4285);
FORCEPROP 2 LASTPIN (-2400 3325) $PN Y26
J 0
(-2390 3335);
DISPLAY 0.617021 (-2390 3335);
PAINT ORANGE (-2390 3335);
FORCEPROP 2 LASTPIN (-2400 3275) $PN AA24
J 0
(-2390 3285);
DISPLAY 0.617021 (-2390 3285);
PAINT ORANGE (-2390 3285);
FORCEPROP 2 LASTPIN (-5400 4075) $PN R42
J 2
(-5410 4085);
DISPLAY 0.617021 (-5410 4085);
PAINT ORANGE (-5410 4085);
FORCEPROP 2 LASTPIN (-5400 4025) $PN R46
J 2
(-5410 4035);
DISPLAY 0.617021 (-5410 4035);
PAINT ORANGE (-5410 4035);
FORCEPROP 2 LASTPIN (-5400 3975) $PN T44
J 2
(-5410 3985);
DISPLAY 0.617021 (-5410 3985);
PAINT ORANGE (-5410 3985);
FORCEPROP 2 LASTPIN (-5400 3925) $PN U46
J 2
(-5410 3935);
DISPLAY 0.617021 (-5410 3935);
PAINT ORANGE (-5410 3935);
FORCEPROP 2 LASTPIN (-5400 3875) $PN V44
J 2
(-5410 3885);
DISPLAY 0.617021 (-5410 3885);
PAINT ORANGE (-5410 3885);
FORCEPROP 2 LASTPIN (-5400 3825) $PN Y45
J 2
(-5410 3835);
DISPLAY 0.617021 (-5410 3835);
PAINT ORANGE (-5410 3835);
FORCEPROP 2 LASTPIN (-5400 3775) $PN Y46
J 2
(-5410 3785);
DISPLAY 0.617021 (-5410 3785);
PAINT ORANGE (-5410 3785);
FORCEPROP 2 LASTPIN (-5400 3725) $PN AA45
J 2
(-5410 3735);
DISPLAY 0.617021 (-5410 3735);
PAINT ORANGE (-5410 3735);
FORCEPROP 2 LASTPIN (-5400 3675) $PN AA46
J 2
(-5410 3685);
DISPLAY 0.617021 (-5410 3685);
PAINT ORANGE (-5410 3685);
FORCEPROP 2 LASTPIN (-5400 3625) $PN AC26
J 2
(-5410 3635);
DISPLAY 0.617021 (-5410 3635);
PAINT ORANGE (-5410 3635);
FORCEPROP 2 LASTPIN (-5400 3575) $PN AJ29
J 2
(-5410 3585);
DISPLAY 0.617021 (-5410 3585);
PAINT ORANGE (-5410 3585);
FORCEPROP 2 LASTPIN (-5400 3525) $PN AM27
J 2
(-5410 3535);
DISPLAY 0.617021 (-5410 3535);
PAINT ORANGE (-5410 3535);
FORCEPROP 2 LASTPIN (-5400 3475) $PN AT39
J 2
(-5410 3485);
DISPLAY 0.617021 (-5410 3485);
PAINT ORANGE (-5410 3485);
FORCEPROP 2 LASTPIN (-5400 3425) $PN AU37
J 2
(-5410 3435);
DISPLAY 0.617021 (-5410 3435);
PAINT ORANGE (-5410 3435);
FORCEPROP 2 LASTPIN (-5400 3375) $PN AU39
J 2
(-5410 3385);
DISPLAY 0.617021 (-5410 3385);
PAINT ORANGE (-5410 3385);
FORCEPROP 2 LASTPIN (-5400 3325) $PN BE48
J 2
(-5410 3335);
DISPLAY 0.617021 (-5410 3335);
PAINT ORANGE (-5410 3335);
FORCEPROP 2 LASTPIN (-5400 3275) $PN BF46
J 2
(-5410 3285);
DISPLAY 0.617021 (-5410 3285);
PAINT ORANGE (-5410 3285);
FORCEPROP 2 LASTPIN (-2400 2625) $PN AJ27
J 0
(-2390 2635);
DISPLAY 0.617021 (-2390 2635);
PAINT ORANGE (-2390 2635);
FORCEPROP 2 LASTPIN (-2400 3025) $PN AG29
J 0
(-2390 3035);
DISPLAY 0.617021 (-2390 3035);
PAINT ORANGE (-2390 3035);
FORCEPROP 2 LASTPIN (-2400 4225) $PN AK29
J 0
(-2390 4235);
DISPLAY 0.617021 (-2390 4235);
PAINT ORANGE (-2390 4235);
FORCEPROP 2 LASTPIN (-2400 4375) $PN AE26
J 0
(-2390 4385);
DISPLAY 0.617021 (-2390 4385);
PAINT ORANGE (-2390 4385);
FORCEPROP 2 LASTPIN (-2400 4325) $PN BD46
J 0
(-2390 4335);
DISPLAY 0.617021 (-2390 4335);
PAINT ORANGE (-2390 4335);
FORCEPROP 2 LASTPIN (-2400 3225) $PN AD24
J 0
(-2390 3235);
DISPLAY 0.617021 (-2390 3235);
PAINT ORANGE (-2390 3235);
FORCEPROP 2 LASTPIN (-2400 3175) $PN BA45
J 0
(-2390 3185);
DISPLAY 0.617021 (-2390 3185);
PAINT ORANGE (-2390 3185);
FORCEPROP 2 LASTPIN (-2400 3125) $PN BA46
J 0
(-2390 3135);
DISPLAY 0.617021 (-2390 3135);
PAINT ORANGE (-2390 3135);
FORCEPROP 2 LASTPIN (-5400 2225) $PN AW48
J 2
(-5410 2235);
DISPLAY 0.617021 (-5410 2235);
PAINT ORANGE (-5410 2235);
FORCEPROP 2 LASTPIN (-5400 2125) $PN AK50
J 2
(-5410 2135);
DISPLAY 0.617021 (-5410 2135);
PAINT ORANGE (-5410 2135);
FORCEPROP 2 LASTPIN (-2400 2575) $PN AG22
J 0
(-2390 2585);
DISPLAY 0.617021 (-2390 2585);
PAINT ORANGE (-2390 2585);
FORCEPROP 2 LASTPIN (-5400 4725) $PN AK45
J 2
(-5410 4735);
DISPLAY 0.617021 (-5410 4735);
PAINT ORANGE (-5410 4735);
FORCEPROP 1 LAST PACK_TYPE BGA1
J 0
(-5350 5075);
PAINT SKYBLUE (-5350 5075);
DISPLAY INVISIBLE (-5350 5075);
FORCEPROP 2 LAST CDS_LIB mstr_u_proc
J 0
(-3900 3075);
PAINT ORANGE (-3900 3075);
DISPLAY INVISIBLE (-3900 3075);
FORCEPROP 0 LAST BOM_COST SB
J 0
(-4350 3825);
DISPLAY 1.361702 (-4350 3825);
PAINT ORANGE (-4350 3825);
DISPLAY INVISIBLE (-4350 3825);
FORCEPROP 2 LAST CDS_LOCATION U7C1
J 0
(-5000 4850);
DISPLAY 0.617021 (-5000 4850);
PAINT AQUA (-5000 4850);
DISPLAY INVISIBLE (-5000 4850);
FORCEPROP 2 LAST SEC 9
J 0
(-3900 5025);
DISPLAY 0.680851 (-3900 5025);
PAINT MONO (-3900 5025);
DISPLAY INVISIBLE (-3900 5025);
FORCEPROP 2 LAST SEC_TYPE BGA1
J 0
(-3900 5025);
DISPLAY 1.021277 (-3900 5025);
PAINT ORANGE (-3900 5025);
DISPLAY INVISIBLE (-3900 5025);
FORCEPROP 1 LAST PATH I63
J 0
(-3900 4975);
PAINT GREEN (-3900 4975);
DISPLAY INVISIBLE (-3900 4975);
FORCEPROP 0 LAST ROOM SB
J 0
(-4350 3725);
DISPLAY 1.361702 (-4350 3725);
PAINT ORANGE (-4350 3725);
DISPLAY INVISIBLE (-4350 3725);
FORCEADD P3V3_STBY..1
(-1150 3025);
FORCEPROP 3 LASTPIN (-1150 2975) SIG_NAME P3V3_STBY\g
J 0
(-1140 2985);
DISPLAY 0.659574 (-1140 2985);
PAINT MONO (-1140 2985);
DISPLAY INVISIBLE (-1140 2985);
FORCEPROP 1 LAST VOLTAGE 3.3V
J 0
(-1195 2982);
DISPLAY 0.340426 (-1195 2982);
PAINT SKYBLUE (-1195 2982);
DISPLAY INVISIBLE (-1195 2982);
FORCEPROP 1 LAST SIZE 1B
J 0
(-1105 3047);
DISPLAY 0.340426 (-1105 3047);
PAINT GREEN (-1105 3047);
DISPLAY INVISIBLE (-1105 3047);
FORCEPROP 2 LAST CDS_LIB mstr_symbols
J 0
(-1150 3025);
PAINT ORANGE (-1150 3025);
DISPLAY INVISIBLE (-1150 3025);
FORCEPROP 1 LAST BODY_TYPE PLUMBING
J 0
(-1195 2982);
DISPLAY 0.340426 (-1195 2982);
PAINT GREEN (-1195 2982);
DISPLAY INVISIBLE (-1195 2982);
FORCEPROP 1 LAST PATH I65
J 0
(-1105 3027);
DISPLAY 0.340426 (-1105 3027);
PAINT GREEN (-1105 3027);
DISPLAY INVISIBLE (-1105 3027);
FORCEPROP 1 LAST HDL_POWER P3V3_STBY
J 0
(-1450 2900);
DISPLAY 0.872340 (-1450 2900);
PAINT ORANGE (-1450 2900);
DISPLAY INVISIBLE (-1450 2900);
FORCEADD P1V05_PCH_STBY_WM26_PLL..1
(-6725 3050);
FORCEPROP 3 LASTPIN (-6725 3000) SIG_NAME P1V05_PCH_STBY_WM26_PLL\g
J 0
(-6715 3010);
DISPLAY 0.659574 (-6715 3010);
PAINT MONO (-6715 3010);
DISPLAY INVISIBLE (-6715 3010);
FORCEPROP 1 LAST VOLTAGE 1.05V
J 0
(-6770 3007);
DISPLAY 0.340426 (-6770 3007);
PAINT SKYBLUE (-6770 3007);
DISPLAY INVISIBLE (-6770 3007);
FORCEPROP 2 LAST CDS_LIB mstr_symbols
J 0
(-6725 3050);
PAINT ORANGE (-6725 3050);
DISPLAY INVISIBLE (-6725 3050);
FORCEPROP 2 LAST BOM_COST SB
J 0
(-6725 3200);
PAINT MONO (-6725 3200);
DISPLAY INVISIBLE (-6725 3200);
FORCEPROP 1 LAST BODY_TYPE PLUMBING
J 0
(-6770 3007);
DISPLAY 0.340426 (-6770 3007);
PAINT GREEN (-6770 3007);
DISPLAY INVISIBLE (-6770 3007);
FORCEPROP 1 LAST PATH I70
J 0
(-6675 3075);
DISPLAY 0.872340 (-6675 3075);
PAINT AQUA (-6675 3075);
DISPLAY INVISIBLE (-6675 3075);
FORCEPROP 2 LAST ROOM SB_DECOUPLING
J 0
(-6725 3150);
DISPLAY 1.361702 (-6725 3150);
PAINT WHITE (-6725 3150);
DISPLAY INVISIBLE (-6725 3150);
FORCEPROP 1 LAST HDL_POWER P1V05_PCH_STBY_WM26_PLL
J 1
(-6725 3100);
DISPLAY 0.872340 (-6725 3100);
PAINT GREEN (-6725 3100);
DISPLAY INVISIBLE (-6725 3100);
FORCEADD P1V05_PCH_STBY_WM20_PLL..1
(-6975 3225);
FORCEPROP 3 LASTPIN (-6975 3175) SIG_NAME P1V05_PCH_STBY_WM20_PLL\g
J 0
(-6965 3185);
DISPLAY 0.659574 (-6965 3185);
PAINT MONO (-6965 3185);
DISPLAY INVISIBLE (-6965 3185);
FORCEPROP 1 LAST VOLTAGE 1.05V
J 0
(-7020 3182);
DISPLAY 0.340426 (-7020 3182);
PAINT SKYBLUE (-7020 3182);
DISPLAY INVISIBLE (-7020 3182);
FORCEPROP 2 LAST BOM_COST SB
J 0
(-6975 3375);
PAINT MONO (-6975 3375);
DISPLAY INVISIBLE (-6975 3375);
FORCEPROP 2 LAST CDS_LIB mstr_symbols
J 0
(-6975 3225);
PAINT ORANGE (-6975 3225);
DISPLAY INVISIBLE (-6975 3225);
FORCEPROP 1 LAST BODY_TYPE PLUMBING
J 0
(-7020 3182);
DISPLAY 0.340426 (-7020 3182);
PAINT GREEN (-7020 3182);
DISPLAY INVISIBLE (-7020 3182);
FORCEPROP 1 LAST PATH I71
J 0
(-6925 3250);
DISPLAY 0.872340 (-6925 3250);
PAINT AQUA (-6925 3250);
DISPLAY INVISIBLE (-6925 3250);
FORCEPROP 2 LAST ROOM SB_DECOUPLING
J 0
(-6975 3325);
DISPLAY 1.361702 (-6975 3325);
PAINT WHITE (-6975 3325);
DISPLAY INVISIBLE (-6975 3325);
FORCEPROP 1 LAST HDL_POWER P1V05_PCH_STBY_WM20_PLL
J 1
(-6975 3275);
DISPLAY 0.872340 (-6975 3275);
PAINT GREEN (-6975 3275);
DISPLAY INVISIBLE (-6975 3275);
FORCEADD P1V05_PCH_STBY_KR_PLL..1
(-7275 3350);
FORCEPROP 3 LASTPIN (-7275 3300) SIG_NAME P1V05_PCH_STBY_KR_PLL\g
J 0
(-7265 3310);
DISPLAY 0.659574 (-7265 3310);
PAINT MONO (-7265 3310);
DISPLAY INVISIBLE (-7265 3310);
FORCEPROP 1 LAST VOLTAGE 1.05V
J 0
(-7320 3307);
DISPLAY 0.340426 (-7320 3307);
PAINT SKYBLUE (-7320 3307);
DISPLAY INVISIBLE (-7320 3307);
FORCEPROP 2 LAST BOM_COST SB
J 0
(-7275 3500);
PAINT MONO (-7275 3500);
DISPLAY INVISIBLE (-7275 3500);
FORCEPROP 2 LAST CDS_LIB mstr_symbols
J 0
(-7275 3350);
PAINT ORANGE (-7275 3350);
DISPLAY INVISIBLE (-7275 3350);
FORCEPROP 1 LAST BODY_TYPE PLUMBING
J 0
(-7320 3307);
DISPLAY 0.340426 (-7320 3307);
PAINT GREEN (-7320 3307);
DISPLAY INVISIBLE (-7320 3307);
FORCEPROP 1 LAST PATH I72
J 0
(-7225 3375);
DISPLAY 0.872340 (-7225 3375);
PAINT AQUA (-7225 3375);
DISPLAY INVISIBLE (-7225 3375);
FORCEPROP 2 LAST ROOM SB_DECOUPLING
J 0
(-7275 3450);
DISPLAY 1.361702 (-7275 3450);
PAINT WHITE (-7275 3450);
DISPLAY INVISIBLE (-7275 3450);
FORCEPROP 1 LAST HDL_POWER P1V05_PCH_STBY_KR_PLL
J 1
(-7275 3400);
DISPLAY 0.872340 (-7275 3400);
PAINT GREEN (-7275 3400);
DISPLAY INVISIBLE (-7275 3400);
FORCEADD P1V05_PCH_STBY_ISCLK_PLL..1
(-7575 3475);
FORCEPROP 3 LASTPIN (-7575 3425) SIG_NAME P1V05_PCH_STBY_ISCLK_PLL\g
J 0
(-7565 3435);
DISPLAY 0.659574 (-7565 3435);
PAINT MONO (-7565 3435);
DISPLAY INVISIBLE (-7565 3435);
FORCEPROP 1 LAST VOLTAGE 1.05V
J 0
(-7620 3432);
DISPLAY 0.340426 (-7620 3432);
PAINT SKYBLUE (-7620 3432);
DISPLAY INVISIBLE (-7620 3432);
FORCEPROP 2 LAST BOM_COST SB
J 0
(-7575 3625);
PAINT MONO (-7575 3625);
DISPLAY INVISIBLE (-7575 3625);
FORCEPROP 2 LAST CDS_LIB mstr_symbols
J 0
(-7575 3475);
PAINT ORANGE (-7575 3475);
DISPLAY INVISIBLE (-7575 3475);
FORCEPROP 1 LAST BODY_TYPE PLUMBING
J 0
(-7620 3432);
DISPLAY 0.340426 (-7620 3432);
PAINT GREEN (-7620 3432);
DISPLAY INVISIBLE (-7620 3432);
FORCEPROP 1 LAST PATH I73
J 0
(-7525 3500);
DISPLAY 0.872340 (-7525 3500);
PAINT AQUA (-7525 3500);
DISPLAY INVISIBLE (-7525 3500);
FORCEPROP 2 LAST ROOM SB_DECOUPLING
J 0
(-7575 3575);
DISPLAY 1.361702 (-7575 3575);
PAINT WHITE (-7575 3575);
DISPLAY INVISIBLE (-7575 3575);
FORCEPROP 1 LAST HDL_POWER P1V05_PCH_STBY_ISCLK_PLL
J 1
(-7575 3525);
DISPLAY 0.872340 (-7575 3525);
PAINT GREEN (-7575 3525);
DISPLAY INVISIBLE (-7575 3525);
FORCEADD P1V05_PCH_STBY_VCCA_XTAL..1
(-7900 3650);
FORCEPROP 3 LASTPIN (-7900 3600) SIG_NAME P1V05_PCH_STBY_VCCA_XTAL\g
J 0
(-7890 3610);
DISPLAY 0.659574 (-7890 3610);
PAINT MONO (-7890 3610);
DISPLAY INVISIBLE (-7890 3610);
FORCEPROP 1 LAST VOLTAGE 1.05V
J 0
(-7945 3607);
DISPLAY 0.340426 (-7945 3607);
PAINT SKYBLUE (-7945 3607);
DISPLAY INVISIBLE (-7945 3607);
FORCEPROP 2 LAST BOM_COST SB
J 0
(-7900 3800);
PAINT MONO (-7900 3800);
DISPLAY INVISIBLE (-7900 3800);
FORCEPROP 2 LAST CDS_LIB mstr_symbols
J 0
(-7900 3650);
PAINT ORANGE (-7900 3650);
DISPLAY INVISIBLE (-7900 3650);
FORCEPROP 1 LAST BODY_TYPE PLUMBING
J 0
(-7945 3607);
DISPLAY 0.340426 (-7945 3607);
PAINT GREEN (-7945 3607);
DISPLAY INVISIBLE (-7945 3607);
FORCEPROP 1 LAST PATH I74
J 0
(-7850 3675);
DISPLAY 0.872340 (-7850 3675);
PAINT AQUA (-7850 3675);
DISPLAY INVISIBLE (-7850 3675);
FORCEPROP 2 LAST ROOM SB_DECOUPLING
J 0
(-7900 3750);
DISPLAY 1.361702 (-7900 3750);
PAINT WHITE (-7900 3750);
DISPLAY INVISIBLE (-7900 3750);
FORCEPROP 1 LAST HDL_POWER P1V05_PCH_STBY_VCCA_XTAL
J 1
(-7900 3700);
DISPLAY 0.872340 (-7900 3700);
PAINT GREEN (-7900 3700);
DISPLAY INVISIBLE (-7900 3700);
FORCEADD P3V3_RTC_STBY..1
(-675 3000);
FORCEPROP 3 LASTPIN (-675 2950) SIG_NAME P3V3_RTC_STBY\g
J 0
(-665 2960);
DISPLAY 0.659574 (-665 2960);
PAINT MONO (-665 2960);
DISPLAY INVISIBLE (-665 2960);
FORCEPROP 1 LAST VOLTAGE 3.3V
J 0
(-720 2957);
DISPLAY 0.340426 (-720 2957);
PAINT SKYBLUE (-720 2957);
DISPLAY INVISIBLE (-720 2957);
FORCEPROP 2 LAST BOM_COST SB
J 0
(-675 3150);
PAINT MONO (-675 3150);
DISPLAY INVISIBLE (-675 3150);
FORCEPROP 2 LAST CDS_LIB mstr_symbols
J 0
(-675 3000);
PAINT ORANGE (-675 3000);
DISPLAY INVISIBLE (-675 3000);
FORCEPROP 1 LAST BODY_TYPE PLUMBING
J 0
(-720 2957);
DISPLAY 0.340426 (-720 2957);
PAINT GREEN (-720 2957);
DISPLAY INVISIBLE (-720 2957);
FORCEPROP 1 LAST PATH I75
J 0
(-625 3025);
DISPLAY 0.872340 (-625 3025);
PAINT AQUA (-625 3025);
DISPLAY INVISIBLE (-625 3025);
FORCEPROP 2 LAST ROOM SB_DECOUPLING
J 0
(-675 3100);
DISPLAY 1.361702 (-675 3100);
PAINT WHITE (-675 3100);
DISPLAY INVISIBLE (-675 3100);
FORCEPROP 1 LAST HDL_POWER P3V3_RTC_STBY
J 1
(-675 3050);
DISPLAY 0.872340 (-675 3050);
PAINT GREEN (-675 3050);
DISPLAY INVISIBLE (-675 3050);
FORCEADD P1V05_PCH_STBY..1
(-1925 3475);
FORCEPROP 3 LASTPIN (-1925 3425) SIG_NAME P1V05_PCH_STBY\g
J 0
(-1915 3435);
DISPLAY 0.659574 (-1915 3435);
PAINT MONO (-1915 3435);
DISPLAY INVISIBLE (-1915 3435);
FORCEPROP 1 LAST VOLTAGE 1.05V
J 0
(-1970 3432);
DISPLAY 0.340426 (-1970 3432);
PAINT SKYBLUE (-1970 3432);
DISPLAY INVISIBLE (-1970 3432);
FORCEPROP 2 LAST CDS_LIB mstr_symbols
J 0
(-1925 3475);
PAINT ORANGE (-1925 3475);
DISPLAY INVISIBLE (-1925 3475);
FORCEPROP 1 LAST BODY_TYPE PLUMBING
J 0
(-1970 3432);
DISPLAY 0.340426 (-1970 3432);
PAINT GREEN (-1970 3432);
DISPLAY INVISIBLE (-1970 3432);
FORCEPROP 1 LAST PATH I76
J 0
(-1875 3500);
DISPLAY 0.872340 (-1875 3500);
PAINT AQUA (-1875 3500);
DISPLAY INVISIBLE (-1875 3500);
FORCEPROP 1 LAST HDL_POWER P1V05_PCH_STBY
J 0
(-1925 3525);
DISPLAY 0.872340 (-1925 3525);
PAINT GREEN (-1925 3525);
DISPLAY INVISIBLE (-1925 3525);
FORCEADD P1V05_PCH_STBY_VCCA_PLL0..1
(-6525 2925);
FORCEPROP 3 LASTPIN (-6525 2875) SIG_NAME P1V05_PCH_STBY_VCCA_PLL0\g
J 0
(-6515 2885);
DISPLAY 0.659574 (-6515 2885);
PAINT MONO (-6515 2885);
DISPLAY INVISIBLE (-6515 2885);
FORCEPROP 1 LAST VOLTAGE 1.05V
J 0
(-6570 2882);
DISPLAY 0.340426 (-6570 2882);
PAINT SKYBLUE (-6570 2882);
DISPLAY INVISIBLE (-6570 2882);
FORCEPROP 2 LAST CDS_LIB mstr_symbols
J 0
(-6525 2925);
PAINT ORANGE (-6525 2925);
DISPLAY INVISIBLE (-6525 2925);
FORCEPROP 2 LAST BOM_COST SB
J 0
(-6525 3075);
PAINT MONO (-6525 3075);
DISPLAY INVISIBLE (-6525 3075);
FORCEPROP 1 LAST BODY_TYPE PLUMBING
J 0
(-6570 2882);
DISPLAY 0.340426 (-6570 2882);
PAINT GREEN (-6570 2882);
DISPLAY INVISIBLE (-6570 2882);
FORCEPROP 1 LAST PATH I77
J 0
(-6475 2950);
DISPLAY 0.872340 (-6475 2950);
PAINT AQUA (-6475 2950);
DISPLAY INVISIBLE (-6475 2950);
FORCEPROP 2 LAST ROOM SB_DECOUPLING
J 0
(-6525 3025);
DISPLAY 1.361702 (-6525 3025);
PAINT WHITE (-6525 3025);
DISPLAY INVISIBLE (-6525 3025);
FORCEPROP 1 LAST HDL_POWER P1V05_PCH_STBY_VCCA_PLL0
J 1
(-6525 2975);
DISPLAY 0.872340 (-6525 2975);
PAINT GREEN (-6525 2975);
DISPLAY INVISIBLE (-6525 2975);
FORCEADD P1V05_PCH_STBY_VCCA_PLL1..1
(-6325 2800);
FORCEPROP 3 LASTPIN (-6325 2750) SIG_NAME P1V05_PCH_STBY_VCCA_PLL1\g
J 0
(-6315 2760);
DISPLAY 0.659574 (-6315 2760);
PAINT MONO (-6315 2760);
DISPLAY INVISIBLE (-6315 2760);
FORCEPROP 1 LAST VOLTAGE 1.05V
J 0
(-6370 2757);
DISPLAY 0.340426 (-6370 2757);
PAINT SKYBLUE (-6370 2757);
DISPLAY INVISIBLE (-6370 2757);
FORCEPROP 2 LAST BOM_COST SB
J 0
(-6325 2950);
PAINT MONO (-6325 2950);
DISPLAY INVISIBLE (-6325 2950);
FORCEPROP 2 LAST CDS_LIB mstr_symbols
J 0
(-6325 2800);
PAINT ORANGE (-6325 2800);
DISPLAY INVISIBLE (-6325 2800);
FORCEPROP 1 LAST BODY_TYPE PLUMBING
J 0
(-6370 2757);
DISPLAY 0.340426 (-6370 2757);
PAINT GREEN (-6370 2757);
DISPLAY INVISIBLE (-6370 2757);
FORCEPROP 1 LAST PATH I78
J 0
(-6275 2825);
DISPLAY 0.872340 (-6275 2825);
PAINT AQUA (-6275 2825);
DISPLAY INVISIBLE (-6275 2825);
FORCEPROP 2 LAST ROOM SB_DECOUPLING
J 0
(-6325 2900);
DISPLAY 1.361702 (-6325 2900);
PAINT WHITE (-6325 2900);
DISPLAY INVISIBLE (-6325 2900);
FORCEPROP 1 LAST HDL_POWER P1V05_PCH_STBY_VCCA_PLL1
J 1
(-6325 2850);
DISPLAY 0.872340 (-6325 2850);
PAINT GREEN (-6325 2850);
DISPLAY INVISIBLE (-6325 2850);
FORCEADD INTEL_CORP_BPAGE..1
(-200 600);
FORCEPROP 1 LAST CDS_CON_LAST_MODIFIED Fri Jun 16 17:48:48 2017
J 0
(-1625 925);
DISPLAY 1.340426 (-1625 925);
PAINT ORANGE (-1625 925);
DISPLAY INVISIBLE (-1625 925);
FORCEPROP 1 LAST CUSTOM_TXT_CDS <CURRENT_DESIGN_SHEET> OF <TOTAL_DESIGN_SHEETS>
J 0
(-700 625);
PAINT ORANGE (-700 625);
FORCEPROP 1 LAST CUSTOM_TXT_CDS <CON_LAST_MODIFIED>
J 0
(-4200 700);
PAINT ORANGE (-4200 700);
FORCEPROP 2 LAST CUSTOM_TXT_CDS <XR_PAGE_TITLE>
J 0
(-8090 5850);
DISPLAY 0.638298 (-8090 5850);
PAINT PINK (-8090 5850);
DISPLAY INVISIBLE (-8090 5850);
FORCEPROP 1 LAST SCH_TITLE LEWISBURG 9/11 PWR
J 0
(-8150 650);
DISPLAY 1.212766 (-8150 650);
PAINT YELLOW (-8150 650);
FORCEPROP 2 LAST CDS_LIB mstr_symbols
J 0
(-200 600);
PAINT ORANGE (-200 600);
DISPLAY INVISIBLE (-200 600);
FORCEPROP 2 LAST PAGE_BORDER TRUE
J 0
(-8090 5850);
DISPLAY 0.851064 (-8090 5850);
PAINT PINK (-8090 5850);
DISPLAY INVISIBLE (-8090 5850);
FORCEPROP 1 LAST COMMENT_BODY TRUE
J 0
(-188 612);
DISPLAY 0.638298 (-188 612);
PAINT PEACH (-188 612);
DISPLAY INVISIBLE (-188 612);
FORCEPROP 2 LAST CDS_XR_PAGE_TITLE CR-122 : @BASEBOARD_FAB2_LIB.BASEBOARD_FAB2(SCH_1):PAGE122
J 0
(-8090 5850);
DISPLAY 0.638298 (-8090 5850);
PAINT PINK (-8090 5850);
DISPLAY INVISIBLE (-8090 5850);
WIRE 16 -1 (-1450 4775)(-1450 4875);
WIRE 16 -1 (-1450 4775)(-1450 4725);
WIRE 16 -1 (-2400 4775)(-1450 4775);
WIRE 16 -1 (-1450 4675)(-1450 4725);
WIRE 16 -1 (-2400 4725)(-1450 4725);
WIRE 16 -1 (-1450 4625)(-1450 4675);
WIRE 16 -1 (-2400 4675)(-1450 4675);
WIRE 16 -1 (-1450 4575)(-1450 4625);
WIRE 16 -1 (-2400 4625)(-1450 4625);
WIRE 16 -1 (-1450 4575)(-1450 4525);
WIRE 16 -1 (-2400 4575)(-1450 4575);
WIRE 16 -1 (-1450 4525)(-1450 4475);
WIRE 16 -1 (-2400 4525)(-1450 4525);
WIRE 16 -1 (-1450 4475)(-1450 4375);
WIRE 16 -1 (-2400 4475)(-1450 4475);
WIRE 16 -1 (-1450 4375)(-1450 4325);
WIRE 16 -1 (-2400 4375)(-1450 4375);
WIRE 16 -1 (-1450 4275)(-1450 4325);
WIRE 16 -1 (-2400 4325)(-1450 4325);
WIRE 16 -1 (-1450 4225)(-1450 4275);
WIRE 16 -1 (-2400 4275)(-1450 4275);
WIRE 16 -1 (-1450 4225)(-1450 4125);
WIRE 16 -1 (-2400 4225)(-1450 4225);
WIRE 16 -1 (-1450 4125)(-1450 4075);
WIRE 16 -1 (-2400 4125)(-1450 4125);
WIRE 16 -1 (-2400 4075)(-1450 4075);
WIRE 16 -1 (-5650 5175)(-5650 4775);
WIRE 16 -1 (-5650 4775)(-5650 4725);
WIRE 16 -1 (-5650 4775)(-5400 4775);
WIRE 16 -1 (-5650 4725)(-5650 4675);
WIRE 16 -1 (-5650 4725)(-5400 4725);
WIRE 16 -1 (-5650 4675)(-5650 4625);
WIRE 16 -1 (-5650 4675)(-5400 4675);
WIRE 16 -1 (-5650 4625)(-5650 4575);
WIRE 16 -1 (-5650 4625)(-5400 4625);
WIRE 16 -1 (-5650 4575)(-5650 4525);
WIRE 16 -1 (-5650 4575)(-5400 4575);
WIRE 16 -1 (-5650 4525)(-5650 4475);
WIRE 16 -1 (-5650 4525)(-5400 4525);
WIRE 16 -1 (-5650 4475)(-5650 4425);
WIRE 16 -1 (-5650 4475)(-5400 4475);
WIRE 16 -1 (-5650 4425)(-5650 4375);
WIRE 16 -1 (-5650 4425)(-5400 4425);
WIRE 16 -1 (-5650 4375)(-5650 4325);
WIRE 16 -1 (-5650 4375)(-5400 4375);
WIRE 16 -1 (-5650 4325)(-5650 4275);
WIRE 16 -1 (-5650 4325)(-5400 4325);
WIRE 16 -1 (-5650 4275)(-5650 4225);
WIRE 16 -1 (-5650 4275)(-5400 4275);
WIRE 16 -1 (-5650 4225)(-5650 4175);
WIRE 16 -1 (-5650 4225)(-5400 4225);
WIRE 16 -1 (-5650 4175)(-5650 4075);
WIRE 16 -1 (-5650 4175)(-5400 4175);
WIRE 16 -1 (-5650 4075)(-5650 4025);
WIRE 16 -1 (-5400 4075)(-5650 4075);
WIRE 16 -1 (-5650 4025)(-5650 3975);
WIRE 16 -1 (-5400 4025)(-5650 4025);
WIRE 16 -1 (-5650 3975)(-5650 3925);
WIRE 16 -1 (-5400 3975)(-5650 3975);
WIRE 16 -1 (-5650 3925)(-5650 3875);
WIRE 16 -1 (-5400 3925)(-5650 3925);
WIRE 16 -1 (-5650 3875)(-5650 3825);
WIRE 16 -1 (-5400 3875)(-5650 3875);
WIRE 16 -1 (-5650 3825)(-5650 3775);
WIRE 16 -1 (-5400 3825)(-5650 3825);
WIRE 16 -1 (-5650 3775)(-5650 3725);
WIRE 16 -1 (-5400 3775)(-5650 3775);
WIRE 16 -1 (-5650 3725)(-5650 3675);
WIRE 16 -1 (-5400 3725)(-5650 3725);
WIRE 16 -1 (-5650 3625)(-5650 3675);
WIRE 16 -1 (-5650 3675)(-5400 3675);
WIRE 16 -1 (-5650 3575)(-5650 3625);
WIRE 16 -1 (-5400 3625)(-5650 3625);
WIRE 16 -1 (-5650 3525)(-5650 3575);
WIRE 16 -1 (-5650 3575)(-5400 3575);
WIRE 16 -1 (-5650 3475)(-5650 3525);
WIRE 16 -1 (-5400 3525)(-5650 3525);
WIRE 16 -1 (-5650 3425)(-5650 3475);
WIRE 16 -1 (-5650 3475)(-5400 3475);
WIRE 16 -1 (-5650 3425)(-5650 3375);
WIRE 16 -1 (-5650 3425)(-5400 3425);
WIRE 16 -1 (-5650 3375)(-5650 3325);
WIRE 16 -1 (-5650 3375)(-5400 3375);
WIRE 16 -1 (-5650 3325)(-5650 3275);
WIRE 16 -1 (-5650 3325)(-5400 3325);
WIRE 16 -1 (-5650 3275)(-5650 3175);
WIRE 16 -1 (-5650 3275)(-5400 3275);
WIRE 16 -1 (-5650 3125)(-5650 3175);
WIRE 16 -1 (-5400 3175)(-5650 3175);
WIRE 16 -1 (-5650 3075)(-5650 3125);
WIRE 16 -1 (-5400 3125)(-5650 3125);
WIRE 16 -1 (-5650 3025)(-5650 3075);
WIRE 16 -1 (-5650 3075)(-5400 3075);
WIRE 16 -1 (-5650 2975)(-5650 3025);
WIRE 16 -1 (-5650 3025)(-5400 3025);
WIRE 16 -1 (-5650 2975)(-5650 2925);
WIRE 16 -1 (-5650 2975)(-5400 2975);
WIRE 16 -1 (-5650 2925)(-5650 2875);
WIRE 16 -1 (-5400 2925)(-5650 2925);
WIRE 16 -1 (-5650 2875)(-5650 2775);
WIRE 16 -1 (-5400 2875)(-5650 2875);
WIRE 16 -1 (-5650 2775)(-5650 2725);
WIRE 16 -1 (-5650 2775)(-5400 2775);
WIRE 16 -1 (-5650 2725)(-5650 2625);
WIRE 16 -1 (-5650 2725)(-5400 2725);
WIRE 16 -1 (-5650 2625)(-5650 2275);
WIRE 16 -1 (-5650 2625)(-5400 2625);
WIRE 16 -1 (-5650 2275)(-5650 2075);
WIRE 16 -1 (-5650 2275)(-5400 2275);
WIRE 16 -1 (-5650 2075)(-5400 2075);
WIRE 16 -1 (-1150 2725)(-1150 2975);
WIRE 16 -1 (-2150 2725)(-1150 2725);
WIRE 16 -1 (-2150 2725)(-2150 2775);
WIRE 16 -1 (-2400 2725)(-2150 2725);
WIRE 16 -1 (-2150 2875)(-2150 2775);
WIRE 16 -1 (-2150 2775)(-2400 2775);
WIRE 16 -1 (-2150 2925)(-2150 2875);
WIRE 16 -1 (-2400 2875)(-2150 2875);
WIRE 16 -1 (-2150 3025)(-2150 2925);
WIRE 16 -1 (-2400 2925)(-2150 2925);
WIRE 16 -1 (-2150 3125)(-2150 3025);
WIRE 16 -1 (-2400 3025)(-2150 3025);
WIRE 16 -1 (-2150 3125)(-2150 3175);
WIRE 16 -1 (-2150 3125)(-2400 3125);
WIRE 16 -1 (-2150 3175)(-2150 3225);
WIRE 16 -1 (-2150 3175)(-2400 3175);
WIRE 16 -1 (-2150 3425)(-2150 3225);
WIRE 16 -1 (-2400 3225)(-2150 3225);
WIRE 16 -1 (-2150 3475)(-2150 3425);
WIRE 16 -1 (-2400 3425)(-2150 3425);
WIRE 16 -1 (-2150 3525)(-2150 3475);
WIRE 16 -1 (-2400 3475)(-2150 3475);
WIRE 16 -1 (-2150 3575)(-2150 3525);
WIRE 16 -1 (-2400 3525)(-2150 3525);
WIRE 16 -1 (-2150 3625)(-2150 3575);
WIRE 16 -1 (-2400 3575)(-2150 3575);
WIRE 16 -1 (-2150 3675)(-2150 3625);
WIRE 16 -1 (-2400 3625)(-2150 3625);
WIRE 16 -1 (-2150 3725)(-2150 3675);
WIRE 16 -1 (-2400 3675)(-2150 3675);
WIRE 16 -1 (-2150 3775)(-2150 3725);
WIRE 16 -1 (-2400 3725)(-2150 3725);
WIRE 16 -1 (-2150 3825)(-2150 3775);
WIRE 16 -1 (-2400 3775)(-2150 3775);
WIRE 16 -1 (-2150 3825)(-2150 3875);
WIRE 16 -1 (-2400 3825)(-2150 3825);
WIRE 16 -1 (-2400 3875)(-2150 3875);
WIRE 16 -1 (-6725 3000)(-6725 2375);
WIRE 16 -1 (-6725 2375)(-5900 2375);
WIRE 16 -1 (-5900 2375)(-5900 2325);
WIRE 16 -1 (-5900 2375)(-5400 2375);
WIRE 16 -1 (-5900 2225)(-5900 2325);
WIRE 16 -1 (-5900 2325)(-5400 2325);
WIRE 16 -1 (-5900 2225)(-5400 2225);
WIRE 16 -1 (-6975 3175)(-6975 2125);
WIRE 16 -1 (-5775 2125)(-6975 2125);
WIRE 16 -1 (-5775 2125)(-5775 2025);
WIRE 16 -1 (-5775 2125)(-5400 2125);
WIRE 16 -1 (-5400 2025)(-5775 2025);
WIRE 16 -1 (-7275 3300)(-7275 1925);
WIRE 16 -1 (-5650 1925)(-7275 1925);
WIRE 16 -1 (-5650 1925)(-5650 1875);
WIRE 16 -1 (-5400 1925)(-5650 1925);
WIRE 16 -1 (-5650 1875)(-5650 1825);
WIRE 16 -1 (-5400 1875)(-5650 1875);
WIRE 16 -1 (-5650 1825)(-5650 1775);
WIRE 16 -1 (-5400 1825)(-5650 1825);
WIRE 16 -1 (-5400 1775)(-5650 1775);
WIRE 16 -1 (-7575 1675)(-7575 3425);
WIRE 16 -1 (-5800 1675)(-7575 1675);
WIRE 16 -1 (-5800 1675)(-5800 1625);
WIRE 16 -1 (-5800 1675)(-5400 1675);
WIRE 16 -1 (-5800 1625)(-5800 1575);
WIRE 16 -1 (-5400 1625)(-5800 1625);
WIRE 16 -1 (-5800 1575)(-5800 1525);
WIRE 16 -1 (-5400 1575)(-5800 1575);
WIRE 16 -1 (-5800 1525)(-5800 1475);
WIRE 16 -1 (-5400 1525)(-5800 1525);
WIRE 16 -1 (-5400 1475)(-5800 1475);
WIRE 16 -1 (-7900 3600)(-7900 1375);
WIRE 16 -1 (-7900 1375)(-5400 1375);
WIRE 16 -1 (-675 2950)(-675 2625);
WIRE 16 -1 (-2400 2625)(-675 2625);
WIRE 16 -1 (-1925 3325)(-1925 3425);
WIRE 16 -1 (-1925 3275)(-1925 3325);
WIRE 16 -1 (-2400 3325)(-1925 3325);
WIRE 16 -1 (-2400 3275)(-1925 3275);
WIRE 16 -1 (-6525 2875)(-6525 2475);
WIRE 16 -1 (-6525 2475)(-5400 2475);
WIRE 16 -1 (-6325 2525)(-6325 2750);
WIRE 16 -1 (-6325 2525)(-5400 2525);
WIRE 16 -1 (-2400 2325)(-1425 2325);
FORCEPROP 2 LAST SIG_NAME TP_PCH_RSVD30
J 0
(-1725 2335);
DISPLAY 0.617021 (-1725 2335);
PAINT ORANGE (-1725 2335);
FORCEPROP 2 LASTPROP $XRERR UNIQUE?
J 0
(-1395 2325);
DISPLAY 0.638298 (-1395 2325);
PAINT MONO (-1395 2325);
DISPLAY INVISIBLE (-1395 2325);
WIRE 16 -1 (-1425 2275)(-2400 2275);
FORCEPROP 2 LAST SIG_NAME TP_PCH_RSVD28
J 0
(-1725 2285);
DISPLAY 0.617021 (-1725 2285);
PAINT ORANGE (-1725 2285);
FORCEPROP 2 LASTPROP $XRERR UNIQUE?
J 0
(-1395 2275);
DISPLAY 0.638298 (-1395 2275);
PAINT MONO (-1395 2275);
DISPLAY INVISIBLE (-1395 2275);
WIRE 16 -1 (-2400 2375)(-1425 2375);
FORCEPROP 2 LAST SIG_NAME TP_PCH_RSVD29
J 0
(-1725 2385);
DISPLAY 0.617021 (-1725 2385);
PAINT ORANGE (-1725 2385);
FORCEPROP 2 LASTPROP $XRERR UNIQUE?
J 0
(-1395 2375);
DISPLAY 0.638298 (-1395 2375);
PAINT MONO (-1395 2375);
DISPLAY INVISIBLE (-1395 2375);
WIRE 16 -1 (-2400 2425)(-1425 2425);
FORCEPROP 2 LAST SIG_NAME TP_PCH_RSVD31
J 0
(-1725 2435);
DISPLAY 0.617021 (-1725 2435);
PAINT ORANGE (-1725 2435);
FORCEPROP 2 LASTPROP $XRERR UNIQUE?
J 0
(-1395 2425);
DISPLAY 0.638298 (-1395 2425);
PAINT MONO (-1395 2425);
DISPLAY INVISIBLE (-1395 2425);
WIRE 16 -1 (-2400 2475)(-1425 2475);
FORCEPROP 2 LAST SIG_NAME TP_PCH_RSVD58
J 0
(-1725 2485);
DISPLAY 0.617021 (-1725 2485);
PAINT ORANGE (-1725 2485);
FORCEPROP 2 LASTPROP $XRERR UNIQUE?
J 0
(-1395 2475);
DISPLAY 0.638298 (-1395 2475);
PAINT MONO (-1395 2475);
DISPLAY INVISIBLE (-1395 2475);
WIRE 16 -1 (-2400 3975)(-1700 3975);
FORCEPROP 2 LAST SIG_NAME TP_PCH_RSVD59
J 0
(-1960 3985);
DISPLAY 0.617021 (-1960 3985);
PAINT ORANGE (-1960 3985);
FORCEPROP 2 LASTPROP $XRERR UNIQUE?
J 0
(-1670 3975);
DISPLAY 0.638298 (-1670 3975);
PAINT MONO (-1670 3975);
DISPLAY INVISIBLE (-1670 3975);
WIRE 16 -1 (-2400 2575)(-1300 2575);
FORCEPROP 2 LAST SIG_NAME A_PVCCRTC_EXT_CAP
J 0
(-1735 2585);
DISPLAY 0.617021 (-1735 2585);
PAINT ORANGE (-1735 2585);
DOT 1 (-1450 4725);
DOT 1 (-1450 4675);
DOT 1 (-2150 3525);
DOT 1 (-2150 3625);
DOT 1 (-2150 3575);
DOT 1 (-5650 4675);
DOT 1 (-5650 4625);
DOT 1 (-2150 3025);
DOT 1 (-2150 2875);
DOT 1 (-5650 3425);
DOT 1 (-2150 2925);
DOT 1 (-1925 3325);
DOT 1 (-2150 3475);
DOT 1 (-2150 2775);
DOT 1 (-2150 2725);
DOT 1 (-5650 2975);
DOT 1 (-1450 4125);
DOT 1 (-2150 3675);
DOT 1 (-5800 1525);
DOT 1 (-5800 1575);
DOT 1 (-5650 1875);
DOT 1 (-5650 2925);
DOT 1 (-5650 3075);
DOT 1 (-5650 3125);
DOT 1 (-5650 3175);
DOT 1 (-5650 3325);
DOT 1 (-5650 3275);
DOT 1 (-5650 3475);
DOT 1 (-5650 3525);
DOT 1 (-5650 3675);
DOT 1 (-5650 3625);
DOT 1 (-5650 3725);
DOT 1 (-5650 3775);
DOT 1 (-5650 3825);
DOT 1 (-5650 3875);
DOT 1 (-5650 3925);
DOT 1 (-5650 3975);
DOT 1 (-5650 4025);
DOT 1 (-5650 4075);
DOT 1 (-5650 4175);
DOT 1 (-5650 4225);
DOT 1 (-5650 4275);
DOT 1 (-5650 4375);
DOT 1 (-5650 4425);
DOT 1 (-5650 4475);
DOT 1 (-5650 4575);
DOT 1 (-5650 4525);
DOT 1 (-5650 4725);
DOT 1 (-5650 4775);
DOT 1 (-2150 3225);
DOT 1 (-2150 3425);
DOT 1 (-2150 3725);
DOT 1 (-1450 4225);
DOT 1 (-1450 4275);
DOT 1 (-1450 4325);
DOT 1 (-1450 4475);
DOT 1 (-1450 4375);
DOT 1 (-1450 4575);
DOT 1 (-1450 4525);
DOT 1 (-1450 4625);
DOT 1 (-1450 4775);
DOT 1 (-5650 2875);
DOT 1 (-5650 2775);
DOT 1 (-5650 2725);
DOT 1 (-5800 1625);
DOT 1 (-5900 2325);
DOT 1 (-5900 2375);
DOT 1 (-5650 2625);
DOT 1 (-5800 1675);
DOT 1 (-5650 1825);
DOT 1 (-5650 1925);
DOT 1 (-5775 2125);
DOT 1 (-5650 2275);
DOT 1 (-2150 3125);
DOT 1 (-2150 3175);
DOT 1 (-2150 3775);
DOT 1 (-2150 3825);
DOT 1 (-5650 3025);
DOT 1 (-5650 3375);
DOT 1 (-5650 3575);
DOT 1 (-5650 4325);
FORCENOTE
ROOM=SB
(-8050 875) 0;
DISPLAY LEFT (-8050 875);
DISPLAY 1.021277 (-8050 875);
PAINT PURPLE (-8050 875);
QUIT
